(kicad_pcb
	(version 20260206)
	(generator "pcbnew")
	(generator_version "10.0")
	(general
		(thickness 1.6)
		(legacy_teardrops no)
	)
	(paper "A4")
	(title_block
		(title "04192023_DAF0TMB3IC0_F0TG_MB_C_brd_V02_OCP.brd")
		(comment 1 "Grand Teton / footprint 484 of 8354 (J108), pads 1-48 of 48")
	)
	(layers
		(0 "F.Cu" signal "TOP")
		(4 "In1.Cu" signal "GND")
		(6 "In2.Cu" signal "IN1")
		(8 "In3.Cu" signal "GND1")
		(10 "In4.Cu" signal "IN2")
		(12 "In5.Cu" signal "GND2")
		(14 "In6.Cu" signal "IN3")
		(16 "In7.Cu" signal "GND3")
		(18 "In8.Cu" signal "VCC")
		(20 "In9.Cu" signal "VCC1")
		(22 "In10.Cu" signal "GND4")
		(24 "In11.Cu" signal "IN4")
		(26 "In12.Cu" signal "GND5")
		(28 "In13.Cu" signal "IN5")
		(30 "In14.Cu" signal "GND6")
		(32 "In15.Cu" signal "IN6")
		(34 "In16.Cu" signal "GND7")
		(2 "B.Cu" signal "BOTTOM")
		(9 "F.Adhes" user "F.Adhesive")
		(11 "B.Adhes" user "B.Adhesive")
		(13 "F.Paste" user "Package Geometry/Pastemask Top")
		(15 "B.Paste" user "Package Geometry/Pastemask Bottom")
		(5 "F.SilkS" user "Ref Des/Silkscreen Top")
		(7 "B.SilkS" user "Ref Des/Silkscreen Bottom")
		(1 "F.Mask" user "Board Geometry/Soldermask Top")
		(3 "B.Mask" user "Board Geometry/Soldermask Bottom")
		(17 "Dwgs.User" user "User.Drawings")
		(19 "Cmts.User" user "User.Comments")
		(21 "Eco1.User" user "User.Eco1")
		(23 "Eco2.User" user "User.Eco2")
		(25 "Edge.Cuts" user "Board Geometry/Outline")
		(27 "Margin" user)
		(31 "F.CrtYd" user "Package Geometry/Place Bound Top")
		(29 "B.CrtYd" user "Package Geometry/Place Bound Bottom")
		(35 "F.Fab" user "Ref Des/Assembly Top")
		(33 "B.Fab" user "Ref Des/Assembly Bottom")
	)
	(footprint ""
		(layer "F.Cu")
		(at 314.649612 -440.489848)
		(property "Reference" "J108"
			(at -7.73303 17.692878 0)
			(unlocked yes)
			(layer "F.SilkS")
			(effects
				(font
					(size 0.7874 0.5842)
					(thickness 0.1524)
				)
				(justify left)
			)
		)
		(property "Value" ""
			(at 0 0 0)
			(layer "F.Fab")
			(effects
				(font
					(size 1.27 1.27)
				)
			)
		)
		(duplicate_pad_numbers_are_jumpers no)
		(pad "A1" thru_hole rect
			(at 0 0 180)
			(size 0.766318 0.766318)
			(drill 0.359918)
			(layers "*.Cu" "*.Mask")
			(remove_unused_layers no)
			(net "GPU_3V3IO_RSVD3_FFU")
			(clearance 0.0508)
			(thermal_gap 0.0508)
			(padstack
				(mode front_inner_back)
				(layer "Inner"
					(shape circle)
					(size 0.766318 0.766318)
					(clearance 0.0508)
				)
				(layer "B.Cu"
					(shape rect)
					(size 0.766318 0.766318)
					(clearance 0.0508)
				)
			)
		)
		(pad "A2" thru_hole circle
			(at 1.999996 0.199898 180)
			(size 0.906272 0.906272)
			(drill 0.499872)
			(layers "*.Cu" "*.Mask")
			(remove_unused_layers no)
			(net "GND")
			(clearance 0.0508)
			(thermal_gap 0.0508)
		)
		(pad "A3" thru_hole circle
			(at 3.999992 0 180)
			(size 0.766318 0.766318)
			(drill 0.359918)
			(layers "*.Cu" "*.Mask")
			(remove_unused_layers no)
			(net "PRSNT_CABLE_GPU_A2_N")
			(clearance 0.0508)
			(thermal_gap 0.0508)
		)
		(pad "A4" thru_hole circle
			(at 5.999988 0.199898 180)
			(size 0.906272 0.906272)
			(drill 0.499872)
			(layers "*.Cu" "*.Mask")
			(remove_unused_layers no)
			(net "GND")
			(clearance 0.0508)
			(thermal_gap 0.0508)
		)
		(pad "A5" thru_hole circle
			(at 7.999984 0 180)
			(size 0.766318 0.766318)
			(drill 0.359918)
			(layers "*.Cu" "*.Mask")
			(remove_unused_layers no)
			(net "GPU_3V3IO_RSVD5_FFU")
			(clearance 0.0508)
			(thermal_gap 0.0508)
		)
		(pad "A6" thru_hole circle
			(at 9.99998 0.199898 180)
			(size 0.906272 0.906272)
			(drill 0.499872)
			(layers "*.Cu" "*.Mask")
			(remove_unused_layers no)
			(net "GND")
			(clearance 0.0508)
			(thermal_gap 0.0508)
		)
		(pad "A7" thru_hole circle
			(at 11.999976 0 180)
			(size 0.766318 0.766318)
			(drill 0.359918)
			(layers "*.Cu" "*.Mask")
			(remove_unused_layers no)
			(net "GPU_FPGA_OVERT_N")
			(clearance 0.0508)
			(thermal_gap 0.0508)
		)
		(pad "A8" thru_hole circle
			(at 13.999972 0.199898 180)
			(size 0.906272 0.906272)
			(drill 0.499872)
			(layers "*.Cu" "*.Mask")
			(remove_unused_layers no)
			(net "GND")
			(clearance 0.0508)
			(thermal_gap 0.0508)
		)
		(pad "B1" thru_hole circle
			(at 0 1.199896 180)
			(size 0.906272 0.906272)
			(drill 0.499872)
			(layers "*.Cu" "*.Mask")
			(remove_unused_layers no)
			(net "GND")
			(clearance 0.0508)
			(thermal_gap 0.0508)
		)
		(pad "B3" thru_hole circle
			(at 3.999992 1.199896 180)
			(size 0.906272 0.906272)
			(drill 0.499872)
			(layers "*.Cu" "*.Mask")
			(remove_unused_layers no)
			(net "GND")
			(clearance 0.0508)
			(thermal_gap 0.0508)
		)
		(pad "B5" thru_hole circle
			(at 7.999984 1.199896 180)
			(size 0.906272 0.906272)
			(drill 0.499872)
			(layers "*.Cu" "*.Mask")
			(remove_unused_layers no)
			(net "GND")
			(clearance 0.0508)
			(thermal_gap 0.0508)
		)
		(pad "B7" thru_hole circle
			(at 11.999976 1.199896 180)
			(size 0.906272 0.906272)
			(drill 0.499872)
			(layers "*.Cu" "*.Mask")
			(remove_unused_layers no)
			(net "GND")
			(clearance 0.0508)
			(thermal_gap 0.0508)
		)
		(pad "D2" thru_hole circle
			(at 1.999996 3.800094 180)
			(size 0.906272 0.906272)
			(drill 0.499872)
			(layers "*.Cu" "*.Mask")
			(remove_unused_layers no)
			(net "GND")
			(clearance 0.0508)
			(thermal_gap 0.0508)
		)
		(pad "D4" thru_hole circle
			(at 5.999988 3.800094 180)
			(size 0.906272 0.906272)
			(drill 0.499872)
			(layers "*.Cu" "*.Mask")
			(remove_unused_layers no)
			(net "GND")
			(clearance 0.0508)
			(thermal_gap 0.0508)
		)
		(pad "D6" thru_hole circle
			(at 9.99998 3.800094 180)
			(size 0.906272 0.906272)
			(drill 0.499872)
			(layers "*.Cu" "*.Mask")
			(remove_unused_layers no)
			(net "GND")
			(clearance 0.0508)
			(thermal_gap 0.0508)
		)
		(pad "D8" thru_hole circle
			(at 13.999972 3.800094 180)
			(size 0.906272 0.906272)
			(drill 0.499872)
			(layers "*.Cu" "*.Mask")
			(remove_unused_layers no)
			(net "GND")
			(clearance 0.0508)
			(thermal_gap 0.0508)
		)
		(pad "E1" thru_hole circle
			(at 0 4.800092 180)
			(size 0.906272 0.906272)
			(drill 0.499872)
			(layers "*.Cu" "*.Mask")
			(remove_unused_layers no)
			(net "GND")
			(clearance 0.0508)
			(thermal_gap 0.0508)
		)
		(pad "E3" thru_hole circle
			(at 3.999992 4.800092 180)
			(size 0.906272 0.906272)
			(drill 0.499872)
			(layers "*.Cu" "*.Mask")
			(remove_unused_layers no)
			(net "GND")
			(clearance 0.0508)
			(thermal_gap 0.0508)
		)
		(pad "E5" thru_hole circle
			(at 7.999984 4.800092 180)
			(size 0.906272 0.906272)
			(drill 0.499872)
			(layers "*.Cu" "*.Mask")
			(remove_unused_layers no)
			(net "GND")
			(clearance 0.0508)
			(thermal_gap 0.0508)
		)
		(pad "E7" thru_hole circle
			(at 11.999976 4.800092 180)
			(size 0.906272 0.906272)
			(drill 0.499872)
			(layers "*.Cu" "*.Mask")
			(remove_unused_layers no)
			(net "GND")
			(clearance 0.0508)
			(thermal_gap 0.0508)
		)
		(pad "G2" thru_hole circle
			(at 1.999996 7.400036 180)
			(size 0.906272 0.906272)
			(drill 0.499872)
			(layers "*.Cu" "*.Mask")
			(remove_unused_layers no)
			(net "GND")
			(clearance 0.0508)
			(thermal_gap 0.0508)
		)
		(pad "G4" thru_hole circle
			(at 5.999988 7.400036 180)
			(size 0.906272 0.906272)
			(drill 0.499872)
			(layers "*.Cu" "*.Mask")
			(remove_unused_layers no)
			(net "GND")
			(clearance 0.0508)
			(thermal_gap 0.0508)
		)
		(pad "G6" thru_hole circle
			(at 9.99998 7.400036 180)
			(size 0.906272 0.906272)
			(drill 0.499872)
			(layers "*.Cu" "*.Mask")
			(remove_unused_layers no)
			(net "GND")
			(clearance 0.0508)
			(thermal_gap 0.0508)
		)
		(pad "G8" thru_hole circle
			(at 13.999972 7.400036 180)
			(size 0.906272 0.906272)
			(drill 0.499872)
			(layers "*.Cu" "*.Mask")
			(remove_unused_layers no)
			(net "GND")
			(clearance 0.0508)
			(thermal_gap 0.0508)
		)
		(pad "H1" thru_hole circle
			(at 0 8.400034 180)
			(size 0.906272 0.906272)
			(drill 0.499872)
			(layers "*.Cu" "*.Mask")
			(remove_unused_layers no)
			(net "GND")
			(clearance 0.0508)
			(thermal_gap 0.0508)
		)
		(pad "H3" thru_hole circle
			(at 3.999992 8.400034 180)
			(size 0.906272 0.906272)
			(drill 0.499872)
			(layers "*.Cu" "*.Mask")
			(remove_unused_layers no)
			(net "GND")
			(clearance 0.0508)
			(thermal_gap 0.0508)
		)
		(pad "H5" thru_hole circle
			(at 7.999984 8.400034 180)
			(size 0.906272 0.906272)
			(drill 0.499872)
			(layers "*.Cu" "*.Mask")
			(remove_unused_layers no)
			(net "GND")
			(clearance 0.0508)
			(thermal_gap 0.0508)
		)
		(pad "H7" thru_hole circle
			(at 11.999976 8.400034 180)
			(size 0.906272 0.906272)
			(drill 0.499872)
			(layers "*.Cu" "*.Mask")
			(remove_unused_layers no)
			(net "GND")
			(clearance 0.0508)
			(thermal_gap 0.0508)
		)
		(pad "J2" thru_hole circle
			(at 1.999996 10.999978 180)
			(size 0.906272 0.906272)
			(drill 0.499872)
			(layers "*.Cu" "*.Mask")
			(remove_unused_layers no)
			(net "GND")
			(clearance 0.0508)
			(thermal_gap 0.0508)
		)
		(pad "J4" thru_hole circle
			(at 5.999988 10.999978 180)
			(size 0.906272 0.906272)
			(drill 0.499872)
			(layers "*.Cu" "*.Mask")
			(remove_unused_layers no)
			(net "GND")
			(clearance 0.0508)
			(thermal_gap 0.0508)
		)
		(pad "J6" thru_hole circle
			(at 9.99998 10.999978 180)
			(size 0.906272 0.906272)
			(drill 0.499872)
			(layers "*.Cu" "*.Mask")
			(remove_unused_layers no)
			(net "GND")
			(clearance 0.0508)
			(thermal_gap 0.0508)
		)
		(pad "J8" thru_hole circle
			(at 13.999972 10.999978 180)
			(size 0.906272 0.906272)
			(drill 0.499872)
			(layers "*.Cu" "*.Mask")
			(remove_unused_layers no)
			(net "GND")
			(clearance 0.0508)
			(thermal_gap 0.0508)
		)
		(pad "K1" thru_hole circle
			(at 0 11.999976 180)
			(size 0.906272 0.906272)
			(drill 0.499872)
			(layers "*.Cu" "*.Mask")
			(remove_unused_layers no)
			(net "GND")
			(clearance 0.0508)
			(thermal_gap 0.0508)
		)
		(pad "K3" thru_hole circle
			(at 3.999992 11.999976 180)
			(size 0.906272 0.906272)
			(drill 0.499872)
			(layers "*.Cu" "*.Mask")
			(remove_unused_layers no)
			(net "GND")
			(clearance 0.0508)
			(thermal_gap 0.0508)
		)
		(pad "K5" thru_hole circle
			(at 7.999984 11.999976 180)
			(size 0.906272 0.906272)
			(drill 0.499872)
			(layers "*.Cu" "*.Mask")
			(remove_unused_layers no)
			(net "GND")
			(clearance 0.0508)
			(thermal_gap 0.0508)
		)
		(pad "K7" thru_hole circle
			(at 11.999976 11.999976 180)
			(size 0.906272 0.906272)
			(drill 0.499872)
			(layers "*.Cu" "*.Mask")
			(remove_unused_layers no)
			(net "GND")
			(clearance 0.0508)
			(thermal_gap 0.0508)
		)
		(pad "M2" thru_hole circle
			(at 1.999996 14.59992 180)
			(size 0.906272 0.906272)
			(drill 0.499872)
			(layers "*.Cu" "*.Mask")
			(remove_unused_layers no)
			(net "GND")
			(clearance 0.0508)
			(thermal_gap 0.0508)
		)
		(pad "M4" thru_hole circle
			(at 5.999988 14.59992 180)
			(size 0.906272 0.906272)
			(drill 0.499872)
			(layers "*.Cu" "*.Mask")
			(remove_unused_layers no)
			(net "GND")
			(clearance 0.0508)
			(thermal_gap 0.0508)
		)
		(pad "M6" thru_hole circle
			(at 9.99998 14.59992 180)
			(size 0.906272 0.906272)
			(drill 0.499872)
			(layers "*.Cu" "*.Mask")
			(remove_unused_layers no)
			(net "GND")
			(clearance 0.0508)
			(thermal_gap 0.0508)
		)
		(pad "M8" thru_hole circle
			(at 13.999972 14.59992 180)
			(size 0.906272 0.906272)
			(drill 0.499872)
			(layers "*.Cu" "*.Mask")
			(remove_unused_layers no)
			(net "GND")
			(clearance 0.0508)
			(thermal_gap 0.0508)
		)
		(pad "N1" thru_hole circle
			(at 0 15.599918 180)
			(size 0.906272 0.906272)
			(drill 0.499872)
			(layers "*.Cu" "*.Mask")
			(remove_unused_layers no)
			(net "GND")
			(clearance 0.0508)
			(thermal_gap 0.0508)
		)
		(pad "N2" thru_hole circle
			(at 1.999996 15.80007 180)
			(size 0.766318 0.766318)
			(drill 0.359918)
			(layers "*.Cu" "*.Mask")
			(remove_unused_layers no)
			(net "NC_J108_N2")
			(clearance 0.0508)
			(thermal_gap 0.0508)
		)
		(pad "N3" thru_hole circle
			(at 3.999992 15.599918 180)
			(size 0.906272 0.906272)
			(drill 0.499872)
			(layers "*.Cu" "*.Mask")
			(remove_unused_layers no)
			(net "GND")
			(clearance 0.0508)
			(thermal_gap 0.0508)
		)
		(pad "N4" thru_hole circle
			(at 5.999988 15.80007 180)
			(size 0.766318 0.766318)
			(drill 0.359918)
			(layers "*.Cu" "*.Mask")
			(remove_unused_layers no)
			(net "NC_J108_N4")
			(clearance 0.0508)
			(thermal_gap 0.0508)
		)
		(pad "N5" thru_hole circle
			(at 7.999984 15.599918 180)
			(size 0.906272 0.906272)
			(drill 0.499872)
			(layers "*.Cu" "*.Mask")
			(remove_unused_layers no)
			(net "GND")
			(clearance 0.0508)
			(thermal_gap 0.0508)
		)
		(pad "N6" thru_hole circle
			(at 9.99998 15.80007 180)
			(size 0.766318 0.766318)
			(drill 0.359918)
			(layers "*.Cu" "*.Mask")
			(remove_unused_layers no)
			(net "NC_J108_N6")
			(clearance 0.0508)
			(thermal_gap 0.0508)
		)
		(pad "N7" thru_hole circle
			(at 11.999976 15.599918 180)
			(size 0.906272 0.906272)
			(drill 0.499872)
			(layers "*.Cu" "*.Mask")
			(remove_unused_layers no)
			(net "GND")
			(clearance 0.0508)
			(thermal_gap 0.0508)
		)
		(pad "N8" thru_hole circle
			(at 13.999972 15.80007 180)
			(size 0.766318 0.766318)
			(drill 0.359918)
			(layers "*.Cu" "*.Mask")
			(remove_unused_layers no)
			(net "PRSNT_CABLE_GPU_A3_N")
			(clearance 0.0508)
			(thermal_gap 0.0508)
		)
	)
)
